(kicad_pcb
	(version 20241229)
	(generator "pcbnew")
	(generator_version "9.0")
	(general
		(thickness 1.6642)
		(legacy_teardrops no)
	)
	(paper "A3")
	(title_block
		(title "PolarFire SoM")
		(date "2025-07-22")
		(rev "1.1.4")
		(company "Antmicro Ltd")
		(comment 1 "www.antmicro.com")
		(comment 9 "footprint 70 of 470 (U2), pads 1-82 of 153")
	)
	(layers
		(0 "F.Cu" mixed)
		(4 "In1.Cu" power)
		(6 "In2.Cu" signal)
		(8 "In3.Cu" power)
		(10 "In4.Cu" signal)
		(12 "In5.Cu" power)
		(14 "In6.Cu" power)
		(16 "In7.Cu" signal)
		(18 "In8.Cu" power)
		(20 "In9.Cu" signal)
		(22 "In10.Cu" power)
		(24 "In11.Cu" signal)
		(26 "In12.Cu" signal)
		(2 "B.Cu" mixed)
		(9 "F.Adhes" user "F.Adhesive")
		(11 "B.Adhes" user "B.Adhesive")
		(13 "F.Paste" user)
		(15 "B.Paste" user)
		(5 "F.SilkS" user "F.Silkscreen")
		(7 "B.SilkS" user "B.Silkscreen")
		(1 "F.Mask" user)
		(3 "B.Mask" user)
		(17 "Dwgs.User" user "User.Drawings")
		(19 "Cmts.User" user "User.Comments")
		(21 "Eco1.User" user "User.Eco1")
		(23 "Eco2.User" user "User.Eco2")
		(25 "Edge.Cuts" user)
		(27 "Margin" user)
		(31 "F.CrtYd" user "F.Courtyard")
		(29 "B.CrtYd" user "B.Courtyard")
		(35 "F.Fab" user)
		(33 "B.Fab" user)
	)
	(footprint "antmicro-footprints:BGA-196-153_11.5x13mm_Layout14x14_P0.5x0.5mm"
		(layer "F.Cu")
		(at 214.6935 131.7)
		(property "Reference" "U2"
			(at -5.9435 -5.1 90)
			(layer "F.SilkS")
			(effects
				(font
					(size 0.7 0.7)
					(thickness 0.15)
				)
				(justify left bottom)
			)
		)
		(property "Value" "SDINBDG4-8G"
			(at 0 7.6 0)
			(layer "F.Fab")
			(hide yes)
			(effects
				(font
					(size 0.7 0.7)
					(thickness 0.15)
				)
				(justify left bottom)
			)
		)
		(property "Datasheet" "https://www.infineon.com/dgdl/Infineon-AN98491_Recommended_PCB_Routing_Guidelines_for_a_Infineon_e.MMC_Memory_Device-ApplicationNotes-v05_00-EN.pdf?fileId=8ac78c8c7d718a49017d71baea97084d"
			(at 0 0 0)
			(layer "F.Fab")
			(hide yes)
			(effects
				(font
					(size 1.27 1.27)
					(thickness 0.15)
				)
			)
		)
		(property "Description" "NAND Flash Serial e-MMC 64G-bit SanDisk iNAND 7250 Industrial emmc"
			(at 0 0 0)
			(layer "F.Fab")
			(hide yes)
			(effects
				(font
					(size 1.27 1.27)
					(thickness 0.15)
				)
			)
		)
		(property "Author" "Antmicro"
			(at 0 0 0)
			(layer "F.Fab")
			(hide yes)
			(effects
				(font
					(size 1 1)
					(thickness 0.15)
				)
			)
		)
		(property "License" "Apache-2.0"
			(at 0 0 0)
			(layer "F.Fab")
			(hide yes)
			(effects
				(font
					(size 1 1)
					(thickness 0.15)
				)
			)
		)
		(property "MPN" "SDINBDG4-8G"
			(at 0 0 0)
			(layer "F.Fab")
			(hide yes)
			(effects
				(font
					(size 1 1)
					(thickness 0.15)
				)
			)
		)
		(property "Manufacturer" "SanDisk"
			(at 0 0 0)
			(layer "F.Fab")
			(hide yes)
			(effects
				(font
					(size 1 1)
					(thickness 0.15)
				)
			)
		)
		(property "VSD_class" "eMMC"
			(at 0 0 0)
			(layer "F.Fab")
			(hide yes)
			(effects
				(font
					(size 1 1)
					(thickness 0.15)
				)
			)
		)
		(sheetname "/Memory/")
		(sheetfile "memory.kicad_sch")
		(attr smd)
		(pad "A1" smd circle
			(at -3.25 -3.25)
			(size 0.245 0.245)
			(layers "F.Cu" "F.Mask" "F.Paste")
			(net 699 "unconnected-(U2B-NC-PadA1)")
			(pinfunction "NC")
			(pintype "free")
		)
		(pad "A2" smd circle
			(at -2.75 -3.25)
			(size 0.245 0.245)
			(layers "F.Cu" "F.Mask" "F.Paste")
			(net 663 "unconnected-(U2B-NC-PadA2)")
			(pinfunction "NC")
			(pintype "free")
		)
		(pad "A3" smd circle
			(at -2.25 -3.25)
			(size 0.245 0.245)
			(layers "F.Cu" "F.Mask" "F.Paste")
			(net 208 "/FPGA MSSIO/EMMC.DAT0")
			(pinfunction "DAT0")
			(pintype "bidirectional")
		)
		(pad "A4" smd circle
			(at -1.75 -3.25)
			(size 0.245 0.245)
			(layers "F.Cu" "F.Mask" "F.Paste")
			(net 243 "/FPGA MSSIO/EMMC.DAT1")
			(pinfunction "DAT1")
			(pintype "bidirectional")
		)
		(pad "A5" smd circle
			(at -1.25 -3.25)
			(size 0.245 0.245)
			(layers "F.Cu" "F.Mask" "F.Paste")
			(net 248 "/FPGA MSSIO/EMMC.DAT2")
			(pinfunction "DAT2")
			(pintype "bidirectional")
		)
		(pad "A6" smd circle
			(at -0.75 -3.25)
			(size 0.245 0.245)
			(layers "F.Cu" "F.Mask" "F.Paste")
			(net 417 "GND")
			(pinfunction "VSS")
			(pintype "power_in")
		)
		(pad "A7" smd circle
			(at -0.25 -3.25)
			(size 0.245 0.245)
			(layers "F.Cu" "F.Mask" "F.Paste")
			(net 709 "unconnected-(U2A-RFU-PadA7)")
			(pinfunction "RFU")
			(pintype "no_connect")
		)
		(pad "A8" smd circle
			(at 0.247 -3.25)
			(size 0.245 0.245)
			(layers "F.Cu" "F.Mask" "F.Paste")
			(net 758 "unconnected-(U2B-NC-PadA8)")
			(pinfunction "NC")
			(pintype "free")
		)
		(pad "A9" smd circle
			(at 0.747 -3.25)
			(size 0.245 0.245)
			(layers "F.Cu" "F.Mask" "F.Paste")
			(net 716 "unconnected-(U2B-NC-PadA9)")
			(pinfunction "NC")
			(pintype "free")
		)
		(pad "A10" smd circle
			(at 1.249 -3.25)
			(size 0.245 0.245)
			(layers "F.Cu" "F.Mask" "F.Paste")
			(net 710 "unconnected-(U2B-NC-PadA10)")
			(pinfunction "NC")
			(pintype "free")
		)
		(pad "A11" smd circle
			(at 1.749 -3.25)
			(size 0.245 0.245)
			(layers "F.Cu" "F.Mask" "F.Paste")
			(net 742 "unconnected-(U2B-NC-PadA11)")
			(pinfunction "NC")
			(pintype "free")
		)
		(pad "A12" smd circle
			(at 2.249 -3.25)
			(size 0.245 0.245)
			(layers "F.Cu" "F.Mask" "F.Paste")
			(net 690 "unconnected-(U2B-NC-PadA12)")
			(pinfunction "NC")
			(pintype "free")
		)
		(pad "A13" smd circle
			(at 2.749 -3.25)
			(size 0.245 0.245)
			(layers "F.Cu" "F.Mask" "F.Paste")
			(net 670 "unconnected-(U2B-NC-PadA13)")
			(pinfunction "NC")
			(pintype "free")
		)
		(pad "A14" smd circle
			(at 3.249 -3.25)
			(size 0.245 0.245)
			(layers "F.Cu" "F.Mask" "F.Paste")
			(net 734 "unconnected-(U2B-NC-PadA14)")
			(pinfunction "NC")
			(pintype "free")
		)
		(pad "B1" smd circle
			(at -3.25 -2.75)
			(size 0.245 0.245)
			(layers "F.Cu" "F.Mask" "F.Paste")
			(net 746 "unconnected-(U2B-NC-PadB1)")
			(pinfunction "NC")
			(pintype "free")
		)
		(pad "B2" smd circle
			(at -2.75 -2.75)
			(size 0.245 0.245)
			(layers "F.Cu" "F.Mask" "F.Paste")
			(net 207 "/FPGA MSSIO/EMMC.DAT3")
			(pinfunction "DAT3")
			(pintype "bidirectional")
		)
		(pad "B3" smd circle
			(at -2.25 -2.75)
			(size 0.245 0.245)
			(layers "F.Cu" "F.Mask" "F.Paste")
			(net 250 "/FPGA MSSIO/EMMC.DAT4")
			(pinfunction "DAT4")
			(pintype "bidirectional")
		)
		(pad "B4" smd circle
			(at -1.75 -2.75)
			(size 0.245 0.245)
			(layers "F.Cu" "F.Mask" "F.Paste")
			(net 213 "/FPGA MSSIO/EMMC.DAT5")
			(pinfunction "DAT5")
			(pintype "bidirectional")
		)
		(pad "B5" smd circle
			(at -1.25 -2.75)
			(size 0.245 0.245)
			(layers "F.Cu" "F.Mask" "F.Paste")
			(net 249 "/FPGA MSSIO/EMMC.DAT6")
			(pinfunction "DAT6")
			(pintype "bidirectional")
		)
		(pad "B6" smd circle
			(at -0.75 -2.75)
			(size 0.245 0.245)
			(layers "F.Cu" "F.Mask" "F.Paste")
			(net 214 "/FPGA MSSIO/EMMC.DAT7")
			(pinfunction "DAT7")
			(pintype "bidirectional")
		)
		(pad "B7" smd circle
			(at -0.25 -2.75)
			(size 0.245 0.245)
			(layers "F.Cu" "F.Mask" "F.Paste")
			(net 685 "unconnected-(U2B-NC-PadB7)")
			(pinfunction "NC")
			(pintype "free")
		)
		(pad "B8" smd circle
			(at 0.247 -2.75)
			(size 0.245 0.245)
			(layers "F.Cu" "F.Mask" "F.Paste")
			(net 661 "unconnected-(U2B-NC-PadB8)")
			(pinfunction "NC")
			(pintype "free")
		)
		(pad "B9" smd circle
			(at 0.747 -2.75)
			(size 0.245 0.245)
			(layers "F.Cu" "F.Mask" "F.Paste")
			(net 671 "unconnected-(U2B-NC-PadB9)")
			(pinfunction "NC")
			(pintype "free")
		)
		(pad "B10" smd circle
			(at 1.249 -2.75)
			(size 0.245 0.245)
			(layers "F.Cu" "F.Mask" "F.Paste")
			(net 692 "unconnected-(U2B-NC-PadB10)")
			(pinfunction "NC")
			(pintype "free")
		)
		(pad "B11" smd circle
			(at 1.749 -2.75)
			(size 0.245 0.245)
			(layers "F.Cu" "F.Mask" "F.Paste")
			(net 684 "unconnected-(U2B-NC-PadB11)")
			(pinfunction "NC")
			(pintype "free")
		)
		(pad "B12" smd circle
			(at 2.249 -2.75)
			(size 0.245 0.245)
			(layers "F.Cu" "F.Mask" "F.Paste")
			(net 688 "unconnected-(U2B-NC-PadB12)")
			(pinfunction "NC")
			(pintype "free")
		)
		(pad "B13" smd circle
			(at 2.749 -2.75)
			(size 0.245 0.245)
			(layers "F.Cu" "F.Mask" "F.Paste")
			(net 759 "unconnected-(U2B-NC-PadB13)")
			(pinfunction "NC")
			(pintype "free")
		)
		(pad "B14" smd circle
			(at 3.249 -2.75)
			(size 0.245 0.245)
			(layers "F.Cu" "F.Mask" "F.Paste")
			(net 705 "unconnected-(U2B-NC-PadB14)")
			(pinfunction "NC")
			(pintype "free")
		)
		(pad "C1" smd circle
			(at -3.25 -2.25)
			(size 0.245 0.245)
			(layers "F.Cu" "F.Mask" "F.Paste")
			(net 713 "unconnected-(U2B-NC-PadC1)")
			(pinfunction "NC")
			(pintype "free")
		)
		(pad "C2" smd circle
			(at -2.75 -2.25)
			(size 0.245 0.245)
			(layers "F.Cu" "F.Mask" "F.Paste")
			(net 52 "/Memory/eMMC_VDDI")
			(pinfunction "VDDI")
			(pintype "passive")
		)
		(pad "C3" smd circle
			(at -2.25 -2.25)
			(size 0.245 0.245)
			(layers "F.Cu" "F.Mask" "F.Paste")
			(net 582 "unconnected-(U2B-NC-PadC3)")
			(pinfunction "NC")
			(pintype "free")
		)
		(pad "C4" smd circle
			(at -1.75 -2.25)
			(size 0.245 0.245)
			(layers "F.Cu" "F.Mask" "F.Paste")
			(net 417 "GND")
			(pinfunction "VSSQ")
			(pintype "power_in")
		)
		(pad "C5" smd circle
			(at -1.25 -2.25)
			(size 0.245 0.245)
			(layers "F.Cu" "F.Mask" "F.Paste")
			(net 665 "unconnected-(U2B-NC-PadC5)")
			(pinfunction "NC")
			(pintype "free")
		)
		(pad "C6" smd circle
			(at -0.75 -2.25)
			(size 0.245 0.245)
			(layers "F.Cu" "F.Mask" "F.Paste")
			(net 137 "SD_VDD")
			(pinfunction "VCCQ")
			(pintype "power_in")
		)
		(pad "C7" smd circle
			(at -0.25 -2.25)
			(size 0.245 0.245)
			(layers "F.Cu" "F.Mask" "F.Paste")
			(net 770 "unconnected-(U2B-NC-PadC7)")
			(pinfunction "NC")
			(pintype "free")
		)
		(pad "C8" smd circle
			(at 0.247 -2.25)
			(size 0.245 0.245)
			(layers "F.Cu" "F.Mask" "F.Paste")
			(net 659 "unconnected-(U2B-NC-PadC8)")
			(pinfunction "NC")
			(pintype "free")
		)
		(pad "C9" smd circle
			(at 0.747 -2.25)
			(size 0.245 0.245)
			(layers "F.Cu" "F.Mask" "F.Paste")
			(net 771 "unconnected-(U2B-NC-PadC9)")
			(pinfunction "NC")
			(pintype "free")
		)
		(pad "C10" smd circle
			(at 1.249 -2.25)
			(size 0.245 0.245)
			(layers "F.Cu" "F.Mask" "F.Paste")
			(net 730 "unconnected-(U2B-NC-PadC10)")
			(pinfunction "NC")
			(pintype "free")
		)
		(pad "C11" smd circle
			(at 1.749 -2.25)
			(size 0.245 0.245)
			(layers "F.Cu" "F.Mask" "F.Paste")
			(net 729 "unconnected-(U2B-NC-PadC11)")
			(pinfunction "NC")
			(pintype "free")
		)
		(pad "C12" smd circle
			(at 2.249 -2.25)
			(size 0.245 0.245)
			(layers "F.Cu" "F.Mask" "F.Paste")
			(net 474 "unconnected-(U2B-NC-PadC12)")
			(pinfunction "NC")
			(pintype "free")
		)
		(pad "C13" smd circle
			(at 2.749 -2.25)
			(size 0.245 0.245)
			(layers "F.Cu" "F.Mask" "F.Paste")
			(net 738 "unconnected-(U2B-NC-PadC13)")
			(pinfunction "NC")
			(pintype "free")
		)
		(pad "C14" smd circle
			(at 3.249 -2.25)
			(size 0.245 0.245)
			(layers "F.Cu" "F.Mask" "F.Paste")
			(net 762 "unconnected-(U2B-NC-PadC14)")
			(pinfunction "NC")
			(pintype "free")
		)
		(pad "D1" smd circle
			(at -3.25 -1.75)
			(size 0.245 0.245)
			(layers "F.Cu" "F.Mask" "F.Paste")
			(net 701 "unconnected-(U2B-NC-PadD1)")
			(pinfunction "NC")
			(pintype "free")
		)
		(pad "D2" smd circle
			(at -2.75 -1.75)
			(size 0.245 0.245)
			(layers "F.Cu" "F.Mask" "F.Paste")
			(net 664 "unconnected-(U2B-NC-PadD2)")
			(pinfunction "NC")
			(pintype "free")
		)
		(pad "D3" smd circle
			(at -2.25 -1.75)
			(size 0.245 0.245)
			(layers "F.Cu" "F.Mask" "F.Paste")
			(net 678 "unconnected-(U2B-NC-PadD3)")
			(pinfunction "NC")
			(pintype "free")
		)
		(pad "D4" smd circle
			(at -1.75 -1.75)
			(size 0.245 0.245)
			(layers "F.Cu" "F.Mask" "F.Paste")
			(net 723 "unconnected-(U2B-NC-PadD4)")
			(pinfunction "NC")
			(pintype "free")
		)
		(pad "D12" smd circle
			(at 2.249 -1.75)
			(size 0.245 0.245)
			(layers "F.Cu" "F.Mask" "F.Paste")
			(net 689 "unconnected-(U2B-NC-PadD12)")
			(pinfunction "NC")
			(pintype "free")
		)
		(pad "D13" smd circle
			(at 2.749 -1.75)
			(size 0.245 0.245)
			(layers "F.Cu" "F.Mask" "F.Paste")
			(net 737 "unconnected-(U2B-NC-PadD13)")
			(pinfunction "NC")
			(pintype "free")
		)
		(pad "D14" smd circle
			(at 3.249 -1.75)
			(size 0.245 0.245)
			(layers "F.Cu" "F.Mask" "F.Paste")
			(net 766 "unconnected-(U2B-NC-PadD14)")
			(pinfunction "NC")
			(pintype "free")
		)
		(pad "E1" smd circle
			(at -3.25 -1.25)
			(size 0.245 0.245)
			(layers "F.Cu" "F.Mask" "F.Paste")
			(net 741 "unconnected-(U2B-NC-PadE1)")
			(pinfunction "NC")
			(pintype "free")
		)
		(pad "E2" smd circle
			(at -2.75 -1.25)
			(size 0.245 0.245)
			(layers "F.Cu" "F.Mask" "F.Paste")
			(net 700 "unconnected-(U2B-NC-PadE2)")
			(pinfunction "NC")
			(pintype "free")
		)
		(pad "E3" smd circle
			(at -2.25 -1.25)
			(size 0.245 0.245)
			(layers "F.Cu" "F.Mask" "F.Paste")
			(net 669 "unconnected-(U2B-NC-PadE3)")
			(pinfunction "NC")
			(pintype "free")
		)
		(pad "E5" smd circle
			(at -1.25 -1.25)
			(size 0.245 0.245)
			(layers "F.Cu" "F.Mask" "F.Paste")
			(net 743 "unconnected-(U2A-RFU-PadE5)")
			(pinfunction "RFU")
			(pintype "no_connect")
		)
		(pad "E6" smd circle
			(at -0.75 -1.25)
			(size 0.245 0.245)
			(layers "F.Cu" "F.Mask" "F.Paste")
			(net 50 "+3V3")
			(pinfunction "VCC")
			(pintype "power_in")
		)
		(pad "E7" smd circle
			(at -0.25 -1.25)
			(size 0.245 0.245)
			(layers "F.Cu" "F.Mask" "F.Paste")
			(net 417 "GND")
			(pinfunction "VSS")
			(pintype "passive")
		)
		(pad "E8" smd circle
			(at 0.247 -1.25)
			(size 0.245 0.245)
			(layers "F.Cu" "F.Mask" "F.Paste")
			(net 765 "unconnected-(U2A-RFU-PadE8)")
			(pinfunction "RFU")
			(pintype "no_connect")
		)
		(pad "E9" smd circle
			(at 0.747 -1.25)
			(size 0.245 0.245)
			(layers "F.Cu" "F.Mask" "F.Paste")
			(net 475 "unconnected-(U2A-VSF-PadE9)")
			(pinfunction "VSF")
			(pintype "no_connect")
		)
		(pad "E10" smd circle
			(at 1.249 -1.25)
			(size 0.245 0.245)
			(layers "F.Cu" "F.Mask" "F.Paste")
			(net 673 "unconnected-(U2A-VSF-PadE10)")
			(pinfunction "VSF")
			(pintype "no_connect")
		)
		(pad "E12" smd circle
			(at 2.249 -1.25)
			(size 0.245 0.245)
			(layers "F.Cu" "F.Mask" "F.Paste")
			(net 745 "unconnected-(U2B-NC-PadE12)")
			(pinfunction "NC")
			(pintype "free")
		)
		(pad "E13" smd circle
			(at 2.749 -1.25)
			(size 0.245 0.245)
			(layers "F.Cu" "F.Mask" "F.Paste")
			(net 674 "unconnected-(U2B-NC-PadE13)")
			(pinfunction "NC")
			(pintype "free")
		)
		(pad "E14" smd circle
			(at 3.249 -1.25)
			(size 0.245 0.245)
			(layers "F.Cu" "F.Mask" "F.Paste")
			(net 733 "unconnected-(U2B-NC-PadE14)")
			(pinfunction "NC")
			(pintype "free")
		)
		(pad "F1" smd circle
			(at -3.25 -0.75)
			(size 0.245 0.245)
			(layers "F.Cu" "F.Mask" "F.Paste")
			(net 756 "unconnected-(U2B-NC-PadF1)")
			(pinfunction "NC")
			(pintype "free")
		)
		(pad "F2" smd circle
			(at -2.75 -0.75)
			(size 0.245 0.245)
			(layers "F.Cu" "F.Mask" "F.Paste")
			(net 698 "unconnected-(U2B-NC-PadF2)")
			(pinfunction "NC")
			(pintype "free")
		)
		(pad "F3" smd circle
			(at -2.25 -0.75)
			(size 0.245 0.245)
			(layers "F.Cu" "F.Mask" "F.Paste")
			(net 675 "unconnected-(U2B-NC-PadF3)")
			(pinfunction "NC")
			(pintype "free")
		)
		(pad "F5" smd circle
			(at -1.25 -0.75)
			(size 0.245 0.245)
			(layers "F.Cu" "F.Mask" "F.Paste")
			(net 50 "+3V3")
			(pinfunction "VCC")
			(pintype "passive")
		)
		(pad "F10" smd circle
			(at 1.249 -0.75)
			(size 0.245 0.245)
			(layers "F.Cu" "F.Mask" "F.Paste")
			(net 753 "unconnected-(U2A-VSF-PadF10)")
			(pinfunction "VSF")
			(pintype "no_connect")
		)
		(pad "F12" smd circle
			(at 2.249 -0.75)
			(size 0.245 0.245)
			(layers "F.Cu" "F.Mask" "F.Paste")
			(net 694 "unconnected-(U2B-NC-PadF12)")
			(pinfunction "NC")
			(pintype "free")
		)
		(pad "F13" smd circle
			(at 2.749 -0.75)
			(size 0.245 0.245)
			(layers "F.Cu" "F.Mask" "F.Paste")
			(net 763 "unconnected-(U2B-NC-PadF13)")
			(pinfunction "NC")
			(pintype "free")
		)
		(pad "F14" smd circle
			(at 3.249 -0.75)
			(size 0.245 0.245)
			(layers "F.Cu" "F.Mask" "F.Paste")
			(net 722 "unconnected-(U2B-NC-PadF14)")
			(pinfunction "NC")
			(pintype "free")
		)
		(pad "G1" smd circle
			(at -3.25 -0.25)
			(size 0.245 0.245)
			(layers "F.Cu" "F.Mask" "F.Paste")
			(net 666 "unconnected-(U2B-NC-PadG1)")
			(pinfunction "NC")
			(pintype "free")
		)
		(pad "G2" smd circle
			(at -2.75 -0.25)
			(size 0.245 0.245)
			(layers "F.Cu" "F.Mask" "F.Paste")
			(net 660 "unconnected-(U2B-NC-PadG2)")
			(pinfunction "NC")
			(pintype "free")
		)
		(pad "G3" smd circle
			(at -2.25 -0.25)
			(size 0.245 0.245)
			(layers "F.Cu" "F.Mask" "F.Paste")
			(net 695 "unconnected-(U2A-RFU-PadG3)")
			(pinfunction "RFU")
			(pintype "no_connect")
		)
		(pad "G5" smd circle
			(at -1.25 -0.25)
			(size 0.245 0.245)
			(layers "F.Cu" "F.Mask" "F.Paste")
			(net 417 "GND")
			(pinfunction "VSS")
			(pintype "passive")
		)
		(pad "G10" smd circle
			(at 1.249 -0.25)
			(size 0.245 0.245)
			(layers "F.Cu" "F.Mask" "F.Paste")
			(net 736 "unconnected-(U2A-RFU-PadG10)")
			(pinfunction "RFU")
			(pintype "no_connect")
		)
		(pad "G12" smd circle
			(at 2.249 -0.25)
			(size 0.245 0.245)
			(layers "F.Cu" "F.Mask" "F.Paste")
			(net 668 "unconnected-(U2B-NC-PadG12)")
			(pinfunction "NC")
			(pintype "free")
		)
		(pad "G13" smd circle
			(at 2.749 -0.25)
			(size 0.245 0.245)
			(layers "F.Cu" "F.Mask" "F.Paste")
			(net 714 "unconnected-(U2B-NC-PadG13)")
			(pinfunction "NC")
			(pintype "free")
		)
		(pad "G14" smd circle
			(at 3.249 -0.25)
			(size 0.245 0.245)
			(layers "F.Cu" "F.Mask" "F.Paste")
			(net 711 "unconnected-(U2B-NC-PadG14)")
			(pinfunction "NC")
			(pintype "free")
		)
		(pad "H1" smd circle
			(at -3.25 0.247)
			(size 0.245 0.245)
			(layers "F.Cu" "F.Mask" "F.Paste")
			(net 715 "unconnected-(U2B-NC-PadH1)")
			(pinfunction "NC")
			(pintype "free")
		)
		(pad "H2" smd circle
			(at -2.75 0.247)
			(size 0.245 0.245)
			(layers "F.Cu" "F.Mask" "F.Paste")
			(net 676 "unconnected-(U2B-NC-PadH2)")
			(pinfunction "NC")
			(pintype "free")
		)
		(pad "H3" smd circle
			(at -2.25 0.247)
			(size 0.245 0.245)
			(layers "F.Cu" "F.Mask" "F.Paste")
			(net 731 "unconnected-(U2B-NC-PadH3)")
			(pinfunction "NC")
			(pintype "free")
		)
		(pad "H5" smd circle
			(at -1.25 0.247)
			(size 0.245 0.245)
			(layers "F.Cu" "F.Mask" "F.Paste")
			(net 390 "/FPGA MSSIO/EMMC.STRB")
			(pinfunction "RCLK")
			(pintype "output")
		)
		(pad "H10" smd circle
			(at 1.249 0.247)
			(size 0.245 0.245)
			(layers "F.Cu" "F.Mask" "F.Paste")
			(net 417 "GND")
			(pinfunction "VSS")
			(pintype "passive")
		)
	)
)
